# T6G (Grand Teton) — schematic netlist excerpt (pin names and nets, part order shuffled) for the footprints in the layout excerpt that follows; sources: Cadence DE-HDL packaged netlist, KiCad conversion of 04192023_DAF0TMB3IC0_F0TG_MB_C_brd_V02_OCP.brd

C1878  Q_CAP  0.1UF 25V 10% X7R  pkg 0402  page 143 : A = P3V3_AUX ; B = GND
PC6545  Q_CAP  1UF 16V 10% X6S  pkg C0402  page 364 : A = PV09_RETIMER_CPU1_VCCS ; B = GND

(kicad_pcb
	(version 20260206)
	(generator "pcbnew")
	(generator_version "10.0")
	(general
		(thickness 1.6)
		(legacy_teardrops no)
	)
	(paper "A4")
	(title_block
		(title "04192023_DAF0TMB3IC0_F0TG_MB_C_brd_V02_OCP.brd")
		(comment 1 "Grand Teton / footprints 1334-1335 of 8354")
	)
	(layers
		(0 "F.Cu" signal "TOP")
		(4 "In1.Cu" signal "GND")
		(6 "In2.Cu" signal "IN1")
		(8 "In3.Cu" signal "GND1")
		(10 "In4.Cu" signal "IN2")
		(12 "In5.Cu" signal "GND2")
		(14 "In6.Cu" signal "IN3")
		(16 "In7.Cu" signal "GND3")
		(18 "In8.Cu" signal "VCC")
		(20 "In9.Cu" signal "VCC1")
		(22 "In10.Cu" signal "GND4")
		(24 "In11.Cu" signal "IN4")
		(26 "In12.Cu" signal "GND5")
		(28 "In13.Cu" signal "IN5")
		(30 "In14.Cu" signal "GND6")
		(32 "In15.Cu" signal "IN6")
		(34 "In16.Cu" signal "GND7")
		(2 "B.Cu" signal "BOTTOM")
		(9 "F.Adhes" user "F.Adhesive")
		(11 "B.Adhes" user "B.Adhesive")
		(13 "F.Paste" user "Package Geometry/Pastemask Top")
		(15 "B.Paste" user "Package Geometry/Pastemask Bottom")
		(5 "F.SilkS" user "Ref Des/Silkscreen Top")
		(7 "B.SilkS" user "Ref Des/Silkscreen Bottom")
		(1 "F.Mask" user "Board Geometry/Soldermask Top")
		(3 "B.Mask" user "Board Geometry/Soldermask Bottom")
		(17 "Dwgs.User" user "User.Drawings")
		(19 "Cmts.User" user "User.Comments")
		(21 "Eco1.User" user "User.Eco1")
		(23 "Eco2.User" user "User.Eco2")
		(25 "Edge.Cuts" user "Board Geometry/Outline")
		(27 "Margin" user)
		(31 "F.CrtYd" user "Package Geometry/Place Bound Top")
		(29 "B.CrtYd" user "Package Geometry/Place Bound Bottom")
		(35 "F.Fab" user "Ref Des/Assembly Top")
		(33 "B.Fab" user "Ref Des/Assembly Bottom")
	)
	(footprint ""
		(layer "F.Cu")
		(at 156.30779 -96.012508 90)
		(property "Reference" "C1878"
			(at 0 0 90)
			(layer "F.SilkS")
			(hide yes)
			(effects
				(font
					(size 1.27 1.27)
				)
			)
		)
		(property "Value" ""
			(at 0 0 90)
			(layer "F.Fab")
			(effects
				(font
					(size 1.27 1.27)
				)
			)
		)
		(duplicate_pad_numbers_are_jumpers no)
		(fp_line
			(start 0.7874 -0.4064)
			(end 0.7874 0.4064)
			(stroke
				(width 0.1524)
				(type default)
			)
			(layer "F.SilkS")
		)
		(fp_line
			(start -0.7874 -0.4064)
			(end 0.7874 -0.4064)
			(stroke
				(width 0.1524)
				(type default)
			)
			(layer "F.SilkS")
		)
		(fp_line
			(start 0.7874 0.4064)
			(end -0.7874 0.4064)
			(stroke
				(width 0.1524)
				(type default)
			)
			(layer "F.SilkS")
		)
		(fp_line
			(start -0.7874 0.4064)
			(end -0.7874 -0.4064)
			(stroke
				(width 0.1524)
				(type default)
			)
			(layer "F.SilkS")
		)
		(fp_line
			(start -0.12065 -0.305054)
			(end -0.12065 -0.2794)
			(stroke
				(width 0.1)
				(type default)
			)
			(layer "F.Fab")
		)
		(fp_line
			(start -0.67945 -0.305054)
			(end -0.12065 -0.305054)
			(stroke
				(width 0.1)
				(type default)
			)
			(layer "F.Fab")
		)
		(fp_line
			(start 0.67945 -0.3048)
			(end 0.67945 0.3048)
			(stroke
				(width 0.1)
				(type default)
			)
			(layer "F.Fab")
		)
		(fp_line
			(start 0.12065 -0.3048)
			(end 0.67945 -0.3048)
			(stroke
				(width 0.1)
				(type default)
			)
			(layer "F.Fab")
		)
		(fp_line
			(start 0.12065 -0.2794)
			(end 0.12065 -0.3048)
			(stroke
				(width 0.1)
				(type default)
			)
			(layer "F.Fab")
		)
		(fp_line
			(start -0.12065 -0.2794)
			(end 0.12065 -0.2794)
			(stroke
				(width 0.1)
				(type default)
			)
			(layer "F.Fab")
		)
		(fp_line
			(start 0.120396 0.2794)
			(end -0.12065 0.2794)
			(stroke
				(width 0.1)
				(type default)
			)
			(layer "F.Fab")
		)
		(fp_line
			(start -0.12065 0.2794)
			(end -0.12065 0.3048)
			(stroke
				(width 0.1)
				(type default)
			)
			(layer "F.Fab")
		)
		(fp_line
			(start 0.67945 0.3048)
			(end 0.120396 0.3048)
			(stroke
				(width 0.1)
				(type default)
			)
			(layer "F.Fab")
		)
		(fp_line
			(start 0.120396 0.3048)
			(end 0.120396 0.2794)
			(stroke
				(width 0.1)
				(type default)
			)
			(layer "F.Fab")
		)
		(fp_line
			(start -0.12065 0.3048)
			(end -0.67945 0.3048)
			(stroke
				(width 0.1)
				(type default)
			)
			(layer "F.Fab")
		)
		(fp_line
			(start -0.67945 0.3048)
			(end -0.67945 -0.305054)
			(stroke
				(width 0.1)
				(type default)
			)
			(layer "F.Fab")
		)
		(pad "1" smd circle
			(at -0.40005 0 90)
			(size 0 0)
			(layers "F.Cu" "F.Mask" "F.Paste")
			(net "P3V3_AUX")
		)
		(pad "2" smd circle
			(at 0.40005 0 90)
			(size 0 0)
			(layers "F.Cu" "F.Mask" "F.Paste")
			(net "GND")
		)
	)
	(footprint ""
		(layer "F.Cu")
		(at 11.590782 -405.611584 -90)
		(property "Reference" "PC6545"
			(at 0 0 270)
			(layer "F.SilkS")
			(hide yes)
			(effects
				(font
					(size 1.27 1.27)
				)
			)
		)
		(property "Value" ""
			(at 0 0 270)
			(layer "F.Fab")
			(effects
				(font
					(size 1.27 1.27)
				)
			)
		)
		(duplicate_pad_numbers_are_jumpers no)
		(fp_line
			(start -0.7874 0.4064)
			(end -0.7874 -0.4064)
			(stroke
				(width 0.1524)
				(type default)
			)
			(layer "F.SilkS")
		)
		(fp_line
			(start 0.7874 0.4064)
			(end -0.7874 0.4064)
			(stroke
				(width 0.1524)
				(type default)
			)
			(layer "F.SilkS")
		)
		(fp_line
			(start -0.7874 -0.4064)
			(end 0.7874 -0.4064)
			(stroke
				(width 0.1524)
				(type default)
			)
			(layer "F.SilkS")
		)
		(fp_line
			(start 0.7874 -0.4064)
			(end 0.7874 0.4064)
			(stroke
				(width 0.1524)
				(type default)
			)
			(layer "F.SilkS")
		)
		(fp_line
			(start -0.67945 0.3048)
			(end -0.67945 -0.305054)
			(stroke
				(width 0.1)
				(type default)
			)
			(layer "F.Fab")
		)
		(fp_line
			(start -0.12065 0.3048)
			(end -0.67945 0.3048)
			(stroke
				(width 0.1)
				(type default)
			)
			(layer "F.Fab")
		)
		(fp_line
			(start 0.120396 0.3048)
			(end 0.120396 0.2794)
			(stroke
				(width 0.1)
				(type default)
			)
			(layer "F.Fab")
		)
		(fp_line
			(start 0.67945 0.3048)
			(end 0.120396 0.3048)
			(stroke
				(width 0.1)
				(type default)
			)
			(layer "F.Fab")
		)
		(fp_line
			(start -0.12065 0.2794)
			(end -0.12065 0.3048)
			(stroke
				(width 0.1)
				(type default)
			)
			(layer "F.Fab")
		)
		(fp_line
			(start 0.120396 0.2794)
			(end -0.12065 0.2794)
			(stroke
				(width 0.1)
				(type default)
			)
			(layer "F.Fab")
		)
		(fp_line
			(start -0.12065 -0.2794)
			(end 0.12065 -0.2794)
			(stroke
				(width 0.1)
				(type default)
			)
			(layer "F.Fab")
		)
		(fp_line
			(start 0.12065 -0.2794)
			(end 0.12065 -0.3048)
			(stroke
				(width 0.1)
				(type default)
			)
			(layer "F.Fab")
		)
		(fp_line
			(start 0.12065 -0.3048)
			(end 0.67945 -0.3048)
			(stroke
				(width 0.1)
				(type default)
			)
			(layer "F.Fab")
		)
		(fp_line
			(start 0.67945 -0.3048)
			(end 0.67945 0.3048)
			(stroke
				(width 0.1)
				(type default)
			)
			(layer "F.Fab")
		)
		(fp_line
			(start -0.67945 -0.305054)
			(end -0.12065 -0.305054)
			(stroke
				(width 0.1)
				(type default)
			)
			(layer "F.Fab")
		)
		(fp_line
			(start -0.12065 -0.305054)
			(end -0.12065 -0.2794)
			(stroke
				(width 0.1)
				(type default)
			)
			(layer "F.Fab")
		)
		(pad "1" smd circle
			(at -0.40005 0 270)
			(size 0 0)
			(layers "F.Cu" "F.Mask" "F.Paste")
			(net "PV09_RETIMER_CPU1_VCCS")
		)
		(pad "2" smd circle
			(at 0.40005 0 270)
			(size 0 0)
			(layers "F.Cu" "F.Mask" "F.Paste")
			(net "GND")
		)
	)
)
